(kicad_pcb
	(version 20241229)
	(generator "pcbnew")
	(generator_version "9.0")
	(general
		(thickness 1.61)
		(legacy_teardrops no)
	)
	(paper "A3")
	(title_block
		(title "RDIMM DDR5 Tester")
		(date "2026-05-21")
		(rev "2.2.0")
		(company "Antmicro")
		(comment 9 "footprints 713-716 of 796")
	)
	(layers
		(0 "F.Cu" signal)
		(4 "In1.Cu" power)
		(6 "In2.Cu" mixed)
		(8 "In3.Cu" power)
		(10 "In4.Cu" mixed)
		(12 "In5.Cu" power)
		(14 "In6.Cu" mixed)
		(16 "In7.Cu" power)
		(18 "In8.Cu" power)
		(20 "In9.Cu" mixed)
		(22 "In10.Cu" power)
		(2 "B.Cu" signal)
		(9 "F.Adhes" user "F.Adhesive")
		(11 "B.Adhes" user "B.Adhesive")
		(13 "F.Paste" user)
		(15 "B.Paste" user)
		(5 "F.SilkS" user "F.Silkscreen")
		(7 "B.SilkS" user "B.Silkscreen")
		(1 "F.Mask" user)
		(3 "B.Mask" user)
		(17 "Dwgs.User" user "User.Drawings")
		(19 "Cmts.User" user "User.Comments")
		(21 "Eco1.User" user "User.Eco1")
		(23 "Eco2.User" user "User.Eco2")
		(25 "Edge.Cuts" user)
		(27 "Margin" user)
		(31 "F.CrtYd" user "F.Courtyard")
		(29 "B.CrtYd" user "B.Courtyard")
		(35 "F.Fab" user)
		(33 "B.Fab" user)
	)
	(footprint "antmicro-footprints:C_0402_1005Metric"
		(layer "B.Cu")
		(at 260.524499 156.349 -90)
		(descr "Capacitor SMD 0402")
		(tags "capacitor SMD 0402")
		(property "Reference" "C174"
			(at -1.849 -1.475501 90)
			(layer "B.SilkS")
			(effects
				(font
					(size 0.7 0.7)
					(thickness 0.15)
				)
				(justify left bottom mirror)
			)
		)
		(property "Value" "C_1u_0402"
			(at -1.022927 -2.155213 90)
			(layer "B.Fab")
			(effects
				(font
					(size 0.7 0.7)
					(thickness 0.15)
				)
				(justify left bottom mirror)
			)
		)
		(property "Datasheet" "https://product.tdk.com/en/search/capacitor/ceramic/mlcc/info?part_no=C1005X6S1A105K050BC"
			(at 0 0 270)
			(layer "F.Fab")
			(hide yes)
			(effects
				(font
					(size 1.27 1.27)
					(thickness 0.15)
				)
			)
		)
		(property "Manufacturer" "TDK"
			(at 0 0 270)
			(unlocked yes)
			(layer "B.Fab")
			(hide yes)
			(effects
				(font
					(size 1 1)
					(thickness 0.15)
				)
				(justify mirror)
			)
		)
		(property "MPN" "C1005X6S1A105K050BC"
			(at 0 0 270)
			(unlocked yes)
			(layer "B.Fab")
			(hide yes)
			(effects
				(font
					(size 1 1)
					(thickness 0.15)
				)
				(justify mirror)
			)
		)
		(property "Val" "1u"
			(at 0 0 270)
			(unlocked yes)
			(layer "B.Fab")
			(hide yes)
			(effects
				(font
					(size 1 1)
					(thickness 0.15)
				)
				(justify mirror)
			)
		)
		(property "License" "Apache-2.0"
			(at 0 0 270)
			(unlocked yes)
			(layer "B.Fab")
			(hide yes)
			(effects
				(font
					(size 1 1)
					(thickness 0.15)
				)
				(justify mirror)
			)
		)
		(property "Author" "Antmicro"
			(at 0 0 270)
			(unlocked yes)
			(layer "B.Fab")
			(hide yes)
			(effects
				(font
					(size 1 1)
					(thickness 0.15)
				)
				(justify mirror)
			)
		)
		(property "Voltage" ""
			(at 0 0 270)
			(unlocked yes)
			(layer "B.Fab")
			(hide yes)
			(effects
				(font
					(size 1 1)
					(thickness 0.15)
				)
				(justify mirror)
			)
		)
		(property "Dielectric" ""
			(at 0 0 270)
			(unlocked yes)
			(layer "B.Fab")
			(hide yes)
			(effects
				(font
					(size 1 1)
					(thickness 0.15)
				)
				(justify mirror)
			)
		)
		(sheetname "/Supply/DC-DC IO/")
		(sheetfile "dc-dc-io.kicad_sch")
		(attr smd)
		(fp_rect
			(start -0.925 0.47)
			(end 0.925 -0.47)
			(stroke
				(width 0.05)
				(type default)
			)
			(fill no)
			(layer "B.CrtYd")
		)
		(fp_line
			(start -0.494 0.25)
			(end 0.504 0.25)
			(stroke
				(width 0.15)
				(type solid)
			)
			(layer "B.Fab")
		)
		(fp_line
			(start 0.504 0.25)
			(end 0.504 -0.248)
			(stroke
				(width 0.15)
				(type solid)
			)
			(layer "B.Fab")
		)
		(fp_line
			(start -0.494 -0.248)
			(end -0.494 0.25)
			(stroke
				(width 0.15)
				(type solid)
			)
			(layer "B.Fab")
		)
		(fp_line
			(start 0.504 -0.248)
			(end -0.494 -0.248)
			(stroke
				(width 0.15)
				(type solid)
			)
			(layer "B.Fab")
		)
		(fp_text user "License: Apache-2.0"
			(at -0.939 -5.799 90)
			(layer "B.Fab")
			(effects
				(font
					(size 0.7 0.7)
					(thickness 0.15)
				)
				(justify left bottom mirror)
			)
		)
		(fp_text user "Author: Antmicro"
			(at -0.939 -3.399 90)
			(layer "B.Fab")
			(effects
				(font
					(size 0.7 0.7)
					(thickness 0.15)
				)
				(justify left bottom mirror)
			)
		)
		(fp_text user "${REFERENCE}"
			(at -0.939 -4.599 90)
			(layer "B.Fab")
			(effects
				(font
					(size 0.7 0.7)
					(thickness 0.15)
				)
				(justify left bottom mirror)
			)
		)
		(pad "1" smd roundrect
			(at -0.48 0 270)
			(size 0.59 0.64)
			(layers "B.Cu" "B.Mask" "B.Paste")
			(roundrect_rratio 0.25)
			(net 1 "GND")
			(pintype "passive")
		)
		(pad "2" smd roundrect
			(at 0.48 0 270)
			(size 0.59 0.64)
			(layers "B.Cu" "B.Mask" "B.Paste")
			(roundrect_rratio 0.25)
			(net 36 "/Supply/DC-DC IO/QDCDC2_VCC")
			(pintype "passive")
		)
	)
	(footprint "antmicro-footprints:C_0402_1005Metric"
		(layer "B.Cu")
		(at 163.65 193.299501 90)
		(descr "Capacitor SMD 0402")
		(tags "capacitor SMD 0402")
		(property "Reference" "C232"
			(at 0.994 0.403501 90)
			(layer "B.SilkS")
			(effects
				(font
					(size 0.7 0.7)
					(thickness 0.15)
				)
				(justify right bottom mirror)
			)
		)
		(property "Value" "C_100n_0402"
			(at -1.022927 -2.155213 90)
			(layer "B.Fab")
			(effects
				(font
					(size 0.7 0.7)
					(thickness 0.15)
				)
				(justify right bottom mirror)
			)
		)
		(property "Datasheet" "https://www.murata.com/products/productdetail?partno=GRM155R61H104KE14%23"
			(at 0 0 90)
			(layer "F.Fab")
			(hide yes)
			(effects
				(font
					(size 1.27 1.27)
					(thickness 0.15)
				)
			)
		)
		(property "Manufacturer" "Murata"
			(at 0 0 90)
			(unlocked yes)
			(layer "B.Fab")
			(hide yes)
			(effects
				(font
					(size 1 1)
					(thickness 0.15)
				)
				(justify mirror)
			)
		)
		(property "MPN" "GRM155R61H104KE14D"
			(at 0 0 90)
			(unlocked yes)
			(layer "B.Fab")
			(hide yes)
			(effects
				(font
					(size 1 1)
					(thickness 0.15)
				)
				(justify mirror)
			)
		)
		(property "Val" "100n"
			(at 0 0 90)
			(unlocked yes)
			(layer "B.Fab")
			(hide yes)
			(effects
				(font
					(size 1 1)
					(thickness 0.15)
				)
				(justify mirror)
			)
		)
		(property "License" "Apache-2.0"
			(at 0 0 90)
			(unlocked yes)
			(layer "B.Fab")
			(hide yes)
			(effects
				(font
					(size 1 1)
					(thickness 0.15)
				)
				(justify mirror)
			)
		)
		(property "Author" "Antmicro"
			(at 0 0 90)
			(unlocked yes)
			(layer "B.Fab")
			(hide yes)
			(effects
				(font
					(size 1 1)
					(thickness 0.15)
				)
				(justify mirror)
			)
		)
		(property "Voltage" "50V"
			(at 0 0 90)
			(unlocked yes)
			(layer "B.Fab")
			(hide yes)
			(effects
				(font
					(size 1 1)
					(thickness 0.15)
				)
				(justify mirror)
			)
		)
		(property "Dielectric" "X5R"
			(at 0 0 90)
			(unlocked yes)
			(layer "B.Fab")
			(hide yes)
			(effects
				(font
					(size 1 1)
					(thickness 0.15)
				)
				(justify mirror)
			)
		)
		(sheetname "/FPGA MGT Interface/")
		(sheetfile "fpga-mgt.kicad_sch")
		(attr smd)
		(fp_rect
			(start -0.925 0.47)
			(end 0.925 -0.47)
			(stroke
				(width 0.05)
				(type default)
			)
			(fill no)
			(layer "B.CrtYd")
		)
		(fp_line
			(start 0.504 -0.248)
			(end -0.494 -0.248)
			(stroke
				(width 0.15)
				(type solid)
			)
			(layer "B.Fab")
		)
		(fp_line
			(start -0.494 -0.248)
			(end -0.494 0.25)
			(stroke
				(width 0.15)
				(type solid)
			)
			(layer "B.Fab")
		)
		(fp_line
			(start 0.504 0.25)
			(end 0.504 -0.248)
			(stroke
				(width 0.15)
				(type solid)
			)
			(layer "B.Fab")
		)
		(fp_line
			(start -0.494 0.25)
			(end 0.504 0.25)
			(stroke
				(width 0.15)
				(type solid)
			)
			(layer "B.Fab")
		)
		(fp_text user "License: Apache-2.0"
			(at -0.939 -5.799 270)
			(layer "B.Fab")
			(effects
				(font
					(size 0.7 0.7)
					(thickness 0.15)
				)
				(justify left bottom mirror)
			)
		)
		(fp_text user "Author: Antmicro"
			(at -0.939 -3.399 270)
			(layer "B.Fab")
			(effects
				(font
					(size 0.7 0.7)
					(thickness 0.15)
				)
				(justify left bottom mirror)
			)
		)
		(fp_text user "${REFERENCE}"
			(at -0.939 -4.599 270)
			(layer "B.Fab")
			(effects
				(font
					(size 0.7 0.7)
					(thickness 0.15)
				)
				(justify left bottom mirror)
			)
		)
		(pad "1" smd roundrect
			(at -0.48 0 90)
			(size 0.59 0.64)
			(layers "B.Cu" "B.Mask" "B.Paste")
			(roundrect_rratio 0.25)
			(net 27 "/FPGA MGT Interface/PCIE.TXD0_N")
			(pintype "passive")
		)
		(pad "2" smd roundrect
			(at 0.48 0 90)
			(size 0.59 0.64)
			(layers "B.Cu" "B.Mask" "B.Paste")
			(roundrect_rratio 0.25)
			(net 28 "/FPGA MGT Interface/GTY_225_TX3_N")
			(pintype "passive")
		)
	)
	(footprint "antmicro-footprints:C_0402_1005Metric"
		(layer "B.Cu")
		(at 186.510001 167.45 90)
		(descr "Capacitor SMD 0402")
		(tags "capacitor SMD 0402")
		(property "Reference" "C275"
			(at -4 0.724 90)
			(layer "B.SilkS")
			(effects
				(font
					(size 0.7 0.7)
					(thickness 0.15)
				)
				(justify right bottom mirror)
			)
		)
		(property "Value" "C_100n_0402"
			(at -1.022927 -2.155213 90)
			(layer "B.Fab")
			(effects
				(font
					(size 0.7 0.7)
					(thickness 0.15)
				)
				(justify right bottom mirror)
			)
		)
		(property "Datasheet" "https://www.murata.com/products/productdetail?partno=GRM155R61H104KE14%23"
			(at 0 0 90)
			(layer "F.Fab")
			(hide yes)
			(effects
				(font
					(size 1.27 1.27)
					(thickness 0.15)
				)
			)
		)
		(property "Manufacturer" "Murata"
			(at 0 0 90)
			(unlocked yes)
			(layer "B.Fab")
			(hide yes)
			(effects
				(font
					(size 1 1)
					(thickness 0.15)
				)
				(justify mirror)
			)
		)
		(property "MPN" "GRM155R61H104KE14D"
			(at 0 0 90)
			(unlocked yes)
			(layer "B.Fab")
			(hide yes)
			(effects
				(font
					(size 1 1)
					(thickness 0.15)
				)
				(justify mirror)
			)
		)
		(property "Val" "100n"
			(at 0 0 90)
			(unlocked yes)
			(layer "B.Fab")
			(hide yes)
			(effects
				(font
					(size 1 1)
					(thickness 0.15)
				)
				(justify mirror)
			)
		)
		(property "License" "Apache-2.0"
			(at 0 0 90)
			(unlocked yes)
			(layer "B.Fab")
			(hide yes)
			(effects
				(font
					(size 1 1)
					(thickness 0.15)
				)
				(justify mirror)
			)
		)
		(property "Author" "Antmicro"
			(at 0 0 90)
			(unlocked yes)
			(layer "B.Fab")
			(hide yes)
			(effects
				(font
					(size 1 1)
					(thickness 0.15)
				)
				(justify mirror)
			)
		)
		(property "Voltage" "50V"
			(at 0 0 90)
			(unlocked yes)
			(layer "B.Fab")
			(hide yes)
			(effects
				(font
					(size 1 1)
					(thickness 0.15)
				)
				(justify mirror)
			)
		)
		(property "Dielectric" "X5R"
			(at 0 0 90)
			(unlocked yes)
			(layer "B.Fab")
			(hide yes)
			(effects
				(font
					(size 1 1)
					(thickness 0.15)
				)
				(justify mirror)
			)
		)
		(sheetname "/FPGA MGT Interface/")
		(sheetfile "fpga-mgt.kicad_sch")
		(attr smd)
		(fp_rect
			(start -0.925 0.47)
			(end 0.925 -0.47)
			(stroke
				(width 0.05)
				(type default)
			)
			(fill no)
			(layer "B.CrtYd")
		)
		(fp_line
			(start 0.504 -0.248)
			(end -0.494 -0.248)
			(stroke
				(width 0.15)
				(type solid)
			)
			(layer "B.Fab")
		)
		(fp_line
			(start -0.494 -0.248)
			(end -0.494 0.25)
			(stroke
				(width 0.15)
				(type solid)
			)
			(layer "B.Fab")
		)
		(fp_line
			(start 0.504 0.25)
			(end 0.504 -0.248)
			(stroke
				(width 0.15)
				(type solid)
			)
			(layer "B.Fab")
		)
		(fp_line
			(start -0.494 0.25)
			(end 0.504 0.25)
			(stroke
				(width 0.15)
				(type solid)
			)
			(layer "B.Fab")
		)
		(fp_text user "Author: Antmicro"
			(at -0.939 -3.399 270)
			(layer "B.Fab")
			(effects
				(font
					(size 0.7 0.7)
					(thickness 0.15)
				)
				(justify left bottom mirror)
			)
		)
		(fp_text user "License: Apache-2.0"
			(at -0.939 -5.799 270)
			(layer "B.Fab")
			(effects
				(font
					(size 0.7 0.7)
					(thickness 0.15)
				)
				(justify left bottom mirror)
			)
		)
		(fp_text user "${REFERENCE}"
			(at -0.939 -4.599 270)
			(layer "B.Fab")
			(effects
				(font
					(size 0.7 0.7)
					(thickness 0.15)
				)
				(justify left bottom mirror)
			)
		)
		(pad "1" smd roundrect
			(at -0.48 0 90)
			(size 0.59 0.64)
			(layers "B.Cu" "B.Mask" "B.Paste")
			(roundrect_rratio 0.25)
			(net 246 "/FPGA MGT Interface/HDMI_OUT.D0_P")
			(pintype "passive")
		)
		(pad "2" smd roundrect
			(at 0.48 0 90)
			(size 0.59 0.64)
			(layers "B.Cu" "B.Mask" "B.Paste")
			(roundrect_rratio 0.25)
			(net 632 "/FPGA MGT Interface/HDMI_FPGA.TX0_P")
			(pintype "passive")
		)
	)
	(footprint "antmicro-footprints:C_0402_1005Metric"
		(layer "B.Cu")
		(at 206.64 150.97 90)
		(descr "Capacitor SMD 0402")
		(tags "capacitor SMD 0402")
		(property "Reference" "C205"
			(at 1.05 0.33 90)
			(layer "B.SilkS")
			(effects
				(font
					(size 0.7 0.7)
					(thickness 0.15)
				)
				(justify right bottom mirror)
			)
		)
		(property "Value" "C_100n_0402"
			(at -1.022927 -2.155213 90)
			(layer "B.Fab")
			(effects
				(font
					(size 0.7 0.7)
					(thickness 0.15)
				)
				(justify right bottom mirror)
			)
		)
		(property "Datasheet" "https://www.murata.com/products/productdetail?partno=GRM155R61H104KE14%23"
			(at 0 0 90)
			(layer "F.Fab")
			(hide yes)
			(effects
				(font
					(size 1.27 1.27)
					(thickness 0.15)
				)
			)
		)
		(property "MPN" "GRM155R61H104KE14D"
			(at 0 0 90)
			(unlocked yes)
			(layer "B.Fab")
			(hide yes)
			(effects
				(font
					(size 1 1)
					(thickness 0.15)
				)
				(justify mirror)
			)
		)
		(property "Manufacturer" "Murata"
			(at 0 0 90)
			(unlocked yes)
			(layer "B.Fab")
			(hide yes)
			(effects
				(font
					(size 1 1)
					(thickness 0.15)
				)
				(justify mirror)
			)
		)
		(property "License" "Apache-2.0"
			(at 0 0 90)
			(unlocked yes)
			(layer "B.Fab")
			(hide yes)
			(effects
				(font
					(size 1 1)
					(thickness 0.15)
				)
				(justify mirror)
			)
		)
		(property "Author" "Antmicro"
			(at 0 0 90)
			(unlocked yes)
			(layer "B.Fab")
			(hide yes)
			(effects
				(font
					(size 1 1)
					(thickness 0.15)
				)
				(justify mirror)
			)
		)
		(property "Val" "100n"
			(at 0 0 90)
			(unlocked yes)
			(layer "B.Fab")
			(hide yes)
			(effects
				(font
					(size 1 1)
					(thickness 0.15)
				)
				(justify mirror)
			)
		)
		(property "Voltage" "50V"
			(at 0 0 90)
			(unlocked yes)
			(layer "B.Fab")
			(hide yes)
			(effects
				(font
					(size 1 1)
					(thickness 0.15)
				)
				(justify mirror)
			)
		)
		(property "Dielectric" "X5R"
			(at 0 0 90)
			(unlocked yes)
			(layer "B.Fab")
			(hide yes)
			(effects
				(font
					(size 1 1)
					(thickness 0.15)
				)
				(justify mirror)
			)
		)
		(sheetname "/FPGA Config/")
		(sheetfile "fpga-config.kicad_sch")
		(attr smd)
		(fp_rect
			(start -0.925 0.47)
			(end 0.925 -0.47)
			(stroke
				(width 0.05)
				(type default)
			)
			(fill no)
			(layer "B.CrtYd")
		)
		(fp_line
			(start 0.504 -0.248)
			(end -0.494 -0.248)
			(stroke
				(width 0.15)
				(type solid)
			)
			(layer "B.Fab")
		)
		(fp_line
			(start -0.494 -0.248)
			(end -0.494 0.25)
			(stroke
				(width 0.15)
				(type solid)
			)
			(layer "B.Fab")
		)
		(fp_line
			(start 0.504 0.25)
			(end 0.504 -0.248)
			(stroke
				(width 0.15)
				(type solid)
			)
			(layer "B.Fab")
		)
		(fp_line
			(start -0.494 0.25)
			(end 0.504 0.25)
			(stroke
				(width 0.15)
				(type solid)
			)
			(layer "B.Fab")
		)
		(fp_text user "Author: Antmicro"
			(at -0.939 -3.399 270)
			(layer "B.Fab")
			(effects
				(font
					(size 0.7 0.7)
					(thickness 0.15)
				)
				(justify left bottom mirror)
			)
		)
		(fp_text user "License: Apache-2.0"
			(at -0.939 -5.799 270)
			(layer "B.Fab")
			(effects
				(font
					(size 0.7 0.7)
					(thickness 0.15)
				)
				(justify left bottom mirror)
			)
		)
		(fp_text user "${REFERENCE}"
			(at -0.939 -4.599 270)
			(layer "B.Fab")
			(effects
				(font
					(size 0.7 0.7)
					(thickness 0.15)
				)
				(justify left bottom mirror)
			)
		)
		(pad "1" smd roundrect
			(at -0.48 0 90)
			(size 0.59 0.64)
			(layers "B.Cu" "B.Mask" "B.Paste")
			(roundrect_rratio 0.25)
			(net 1 "GND")
			(pintype "passive")
		)
		(pad "2" smd roundrect
			(at 0.48 0 90)
			(size 0.59 0.64)
			(layers "B.Cu" "B.Mask" "B.Paste")
			(roundrect_rratio 0.25)
			(net 160 "Net-(U30-OUT)")
			(pintype "passive")
		)
	)
)
